FILE_TYPE = CONNECTIVITY;
{Allegro Design Entry HDL 17.2-2016 S081 (4005846) 1/11/2022}
"PAGE_NUMBER" = 46;
0"NC";
1"M_J_CPU1_SA_DQ<31:0>";
2"M_J_CPU1_SB_DQ<31:0>";
3"M_J_CPU1_SA_CB<7:0>";
4"M_J_CPU1_SB_CB<7:0>";
5"M_J_CPU1_SA_DQS_DP<9:0>";
6"M_J_CPU1_SB_DQS_DP<9:0>";
7"M_J_CPU1_SB_CA<6:0>";
8"M_J_CPU1_SA_CA<6:0>";
9"M_J_CPU1_SA_DQS_DN<9:0>";
10"M_J_CPU1_SB_DQS_DN<9:0>";
11"M_J_CPU1_ALERT_N";
12"TP_M_J_CPU1_SA_TEST39J";
13"M_J_CPU1_ALERT_R_N";
14"M_J_CPU1_CLK_DP<0>";
15"M_J_CPU1_CLK_DN<0>";
16"M_J_CPU1_SA_CS_N<0>";
17"M_J_CPU1_SA_CS_N<1>";
18"M_J_CPU1_SA_RSP<0>";
19"M_J_CPU1_SB_CS_N<0>";
20"M_J_CPU1_SB_CS_N<1>";
21"M_J_CPU1_SA_PAR";
22"M_J_CPU1_SB_PAR";
23"M_J_CPU1_SB_RSP<0>";
24"M_J_CPU1_RESET_N";
25"M_J_CPU1_SB_CA<6>";
26"M_J_CPU1_SA_CA<5>";
27"M_J_CPU1_SA_CA<6>";
28"M_J_CPU1_SA_CA<0>";
29"M_J_CPU1_SA_CA<1>";
30"M_J_CPU1_SA_CA<2>";
31"M_J_CPU1_SA_CA<3>";
32"M_J_CPU1_SA_CA<4>";
33"M_J_CPU1_SB_CA<0>";
34"M_J_CPU1_SB_CA<1>";
35"M_J_CPU1_SB_CA<2>";
36"M_J_CPU1_SB_CA<3>";
37"M_J_CPU1_SB_CA<4>";
38"M_J_CPU1_SB_CA<5>";
39"M_J_CPU1_SB_DQS_DN<8>";
40"M_J_CPU1_SB_DQS_DN<9>";
41"M_J_CPU1_SB_DQS_DP<8>";
42"M_J_CPU1_SB_DQS_DP<9>";
43"M_J_CPU1_SB_DQS_DN<4>";
44"M_J_CPU1_SB_DQS_DN<0>";
45"M_J_CPU1_SA_DQS_DN<8>";
46"M_J_CPU1_SA_DQS_DN<9>";
47"M_J_CPU1_SB_DQS_DN<1>";
48"M_J_CPU1_SB_DQS_DN<2>";
49"M_J_CPU1_SB_DQS_DN<3>";
50"M_J_CPU1_SB_DQS_DN<5>";
51"M_J_CPU1_SB_DQS_DN<6>";
52"M_J_CPU1_SB_DQS_DN<7>";
53"M_J_CPU1_SB_DQS_DP<5>";
54"M_J_CPU1_SB_DQS_DP<3>";
55"M_J_CPU1_SB_DQS_DP<4>";
56"M_J_CPU1_SB_DQS_DP<6>";
57"M_J_CPU1_SB_DQS_DP<7>";
58"M_J_CPU1_SA_DQS_DP<8>";
59"M_J_CPU1_SA_DQS_DP<9>";
60"M_J_CPU1_SB_DQS_DP<0>";
61"M_J_CPU1_SB_DQS_DP<1>";
62"M_J_CPU1_SB_DQS_DP<2>";
63"M_J_CPU1_SA_DQS_DN<4>";
64"M_J_CPU1_SA_DQS_DN<5>";
65"M_J_CPU1_SA_DQS_DN<7>";
66"M_J_CPU1_SA_DQS_DN<0>";
67"M_J_CPU1_SA_DQS_DN<1>";
68"M_J_CPU1_SA_DQS_DN<2>";
69"M_J_CPU1_SA_DQS_DN<3>";
70"M_J_CPU1_SA_DQS_DN<6>";
71"M_J_CPU1_SA_DQS_DP<4>";
72"M_J_CPU1_SA_DQS_DP<3>";
73"M_J_CPU1_SA_DQS_DP<5>";
74"M_J_CPU1_SA_DQS_DP<6>";
75"M_J_CPU1_SA_DQS_DP<7>";
76"M_J_CPU1_SA_DQS_DP<0>";
77"M_J_CPU1_SA_DQS_DP<1>";
78"M_J_CPU1_SA_DQS_DP<2>";
79"M_J_CPU1_SA_CB<6>";
80"M_J_CPU1_SA_CB<7>";
81"M_J_CPU1_SB_CB<0>";
82"M_J_CPU1_SB_CB<1>";
83"M_J_CPU1_SB_CB<2>";
84"M_J_CPU1_SB_CB<3>";
85"M_J_CPU1_SB_CB<4>";
86"M_J_CPU1_SB_CB<5>";
87"M_J_CPU1_SB_CB<6>";
88"M_J_CPU1_SB_CB<7>";
89"M_J_CPU1_SA_CB<0>";
90"M_J_CPU1_SA_CB<1>";
91"M_J_CPU1_SA_CB<2>";
92"M_J_CPU1_SA_CB<3>";
93"M_J_CPU1_SA_CB<4>";
94"M_J_CPU1_SA_CB<5>";
95"M_J_CPU1_SB_DQ<19>";
96"M_J_CPU1_SB_DQ<20>";
97"M_J_CPU1_SB_DQ<21>";
98"M_J_CPU1_SB_DQ<22>";
99"M_J_CPU1_SB_DQ<23>";
100"M_J_CPU1_SB_DQ<24>";
101"M_J_CPU1_SB_DQ<25>";
102"M_J_CPU1_SB_DQ<26>";
103"M_J_CPU1_SB_DQ<27>";
104"M_J_CPU1_SB_DQ<28>";
105"M_J_CPU1_SB_DQ<29>";
106"M_J_CPU1_SB_DQ<30>";
107"M_J_CPU1_SB_DQ<31>";
108"M_J_CPU1_SB_DQ<7>";
109"M_J_CPU1_SB_DQ<6>";
110"M_J_CPU1_SB_DQ<5>";
111"M_J_CPU1_SB_DQ<3>";
112"M_J_CPU1_SB_DQ<4>";
113"M_J_CPU1_SB_DQ<1>";
114"M_J_CPU1_SB_DQ<2>";
115"M_J_CPU1_SB_DQ<8>";
116"M_J_CPU1_SB_DQ<9>";
117"M_J_CPU1_SB_DQ<10>";
118"M_J_CPU1_SB_DQ<11>";
119"M_J_CPU1_SB_DQ<12>";
120"M_J_CPU1_SB_DQ<13>";
121"M_J_CPU1_SB_DQ<14>";
122"M_J_CPU1_SB_DQ<15>";
123"M_J_CPU1_SB_DQ<16>";
124"M_J_CPU1_SB_DQ<17>";
125"M_J_CPU1_SB_DQ<18>";
126"M_J_CPU1_SA_DQ<31>";
127"M_J_CPU1_SB_DQ<0>";
128"M_J_CPU1_SA_DQ<22>";
129"M_J_CPU1_SA_DQ<15>";
130"M_J_CPU1_SA_DQ<16>";
131"M_J_CPU1_SA_DQ<17>";
132"M_J_CPU1_SA_DQ<18>";
133"M_J_CPU1_SA_DQ<19>";
134"M_J_CPU1_SA_DQ<20>";
135"M_J_CPU1_SA_DQ<21>";
136"M_J_CPU1_SA_DQ<23>";
137"M_J_CPU1_SA_DQ<24>";
138"M_J_CPU1_SA_DQ<25>";
139"M_J_CPU1_SA_DQ<26>";
140"M_J_CPU1_SA_DQ<27>";
141"M_J_CPU1_SA_DQ<28>";
142"M_J_CPU1_SA_DQ<29>";
143"M_J_CPU1_SA_DQ<30>";
144"M_J_CPU1_SA_DQ<0>";
145"M_J_CPU1_SA_DQ<1>";
146"M_J_CPU1_SA_DQ<2>";
147"M_J_CPU1_SA_DQ<3>";
148"M_J_CPU1_SA_DQ<4>";
149"M_J_CPU1_SA_DQ<5>";
150"M_J_CPU1_SA_DQ<6>";
151"M_J_CPU1_SA_DQ<7>";
152"M_J_CPU1_SA_DQ<8>";
153"M_J_CPU1_SA_DQ<9>";
154"M_J_CPU1_SA_DQ<10>";
155"M_J_CPU1_SA_DQ<11>";
156"M_J_CPU1_SA_DQ<12>";
157"M_J_CPU1_SA_DQ<13>";
158"M_J_CPU1_SA_DQ<14>";
%"GENOA_SP5"
"10","(-4525,3525)","0","pure_quanta","I159";
;
LOCATION"U26"
$SEC"10"
CDS_SEC"10"
PART_TYPE"SMLF"
MATERIAL"IO"
VALUE"SOCKET6096_13568-001"
PART_NUMBER"DGA^6000030"
CDS_LIB"pure_quanta"
CDS_LMAN_SYM_OUTLINE"-650,2525,650,-2525"
NEEDS_NO_SIZE"TRUE";
"TEST39J"
$PN"BF18"12;
"MJB_DATA7"
$PN"CH18"108;
"MJB_DATA6"
$PN"CG16"109;
"MJB_DATA5"
$PN"CG17"110;
"MJB_DQS_H5"
$PN"CF18"53;
"MJB_DQS_L4"
$PN"BW17"43;
"MJB_DQS_L0"
$PN"CE16"44;
"MJA_DATA31"
$PN"AJ17"126;
"MJB_DATA0"
$PN"CB16"127;
"MJB_DATA3"
$PN"CD18"111;
"MJB_DATA4"
$PN"CF16"112;
"MJA_DQS_H4"
$PN"AL16"71;
"MJA_DQS_H8"
$PN"AG17"58;
"MJA_DQS_L4"
$PN"AM16"63;
"MJA_DQS_L5"
$PN"H18"64;
"MJA_DQS_L7"
$PN"Y18"65;
"MJA_DATA22"
$PN"AB16"128;
"MJA_CA5"
$PN"BB16"26;
"MJA_CA6"
$PN"BB18"27;
"MJ0_CLK_H"
$PN"BC16"14;
"MJ0_CLK_L"
$PN"BD16"15;
"MJ1_CLK_H"
$PN"BF16"0;
"MJ1_CLK_L"
$PN"BG16"0;
"MJA0_CS_L0"
$PN"AU16"16;
"MJA0_CS_L1"
$PN"AV18"17;
"MJA0_RSP_L"
$PN"BN17"18;
"MJA1_CS_L0"
$PN"AV16"0;
"MJA1_CS_L1"
$PN"AW17"0;
"MJA1_RSP_L"
$PN"BP18"0;
"MJA_CA0"
$PN"AW16"28;
"MJA_CA1"
$PN"AY16"29;
"MJA_CA2"
$PN"AY18"30;
"MJA_CA3"
$PN"BA17"31;
"MJA_CA4"
$PN"BA16"32;
"MJA_CHECK0"
$PN"AJ16"89;
"MJA_CHECK1"
$PN"AK18"90;
"MJA_CHECK2"
$PN"AK16"91;
"MJA_CHECK3"
$PN"AL17"92;
"MJA_CHECK4"
$PN"AN16"93;
"MJA_CHECK5"
$PN"AP18"94;
"MJA_CHECK6"
$PN"AP16"79;
"MJA_CHECK7"
$PN"AR17"80;
"MJA_DATA0"
$PN"E16"144;
"MJA_DATA1"
$PN"F18"145;
"MJA_DATA2"
$PN"F16"146;
"MJA_DATA3"
$PN"G17"147;
"MJA_DATA4"
$PN"J16"148;
"MJA_DATA5"
$PN"K18"149;
"MJA_DATA6"
$PN"K16"150;
"MJA_DATA7"
$PN"L17"151;
"MJA_DATA8"
$PN"L16"152;
"MJA_DATA9"
$PN"M18"153;
"MJA_DATA10"
$PN"M16"154;
"MJA_DATA11"
$PN"N17"155;
"MJA_DATA12"
$PN"R16"156;
"MJA_DATA13"
$PN"T18"157;
"MJA_DATA14"
$PN"T16"158;
"MJA_DATA15"
$PN"U17"129;
"MJA_DATA16"
$PN"U16"130;
"MJA_DATA17"
$PN"V18"131;
"MJA_DATA18"
$PN"V16"132;
"MJA_DATA19"
$PN"W17"133;
"MJA_DATA20"
$PN"AA16"134;
"MJA_DATA21"
$PN"AB18"135;
"MJA_DATA23"
$PN"AC17"136;
"MJA_DATA24"
$PN"AC16"137;
"MJA_DATA25"
$PN"AD18"138;
"MJA_DATA26"
$PN"AD16"139;
"MJA_DATA27"
$PN"AE17"140;
"MJA_DATA28"
$PN"AG16"141;
"MJA_DATA29"
$PN"AH18"142;
"MJA_DATA30"
$PN"AH16"143;
"MJA_DQS_H0"
$PN"G16"76;
"MJA_DQS_H1"
$PN"N16"77;
"MJA_DQS_H2"
$PN"W16"78;
"MJA_DQS_H3"
$PN"AE16"72;
"MJA_DQS_H5"
$PN"J17"73;
"MJA_DQS_H6"
$PN"R17"74;
"MJA_DQS_H7"
$PN"AA17"75;
"MJA_DQS_H9"
$PN"AN17"59;
"MJA_DQS_L0"
$PN"H16"66;
"MJA_DQS_L1"
$PN"P16"67;
"MJA_DQS_L2"
$PN"Y16"68;
"MJA_DQS_L3"
$PN"AF16"69;
"MJA_DQS_L6"
$PN"P18"70;
"MJA_DQS_L8"
$PN"AF18"45;
"MJA_DQS_L9"
$PN"AM18"46;
"MJA_PAR"
$PN"BC17"21;
"MJB0_CS_L0"
$PN"BM18"19;
"MJB0_CS_L1"
$PN"BN16"20;
"MJB0_RSP_L"
$PN"BP16"23;
"MJB1_CS_L0"
$PN"BL16"0;
"MJB1_CS_L1"
$PN"BM16"0;
"MJB1_RSP_L"
$PN"BR16"0;
"MJB_CA0"
$PN"BG17"33;
"MJB_CA1"
$PN"BH18"34;
"MJB_CA2"
$PN"BH16"35;
"MJB_CA3"
$PN"BJ16"36;
"MJB_CA4"
$PN"BJ17"37;
"MJB_CA5"
$PN"BK18"38;
"MJB_CA6"
$PN"BK16"25;
"MJB_CHECK0"
$PN"BY16"81;
"MJB_CHECK1"
$PN"CA17"82;
"MJB_CHECK2"
$PN"CA16"83;
"MJB_CHECK3"
$PN"CB18"84;
"MJB_CHECK4"
$PN"BT16"85;
"MJB_CHECK5"
$PN"BU17"86;
"MJB_CHECK6"
$PN"BU16"87;
"MJB_CHECK7"
$PN"BV18"88;
"MJB_DATA1"
$PN"CC17"113;
"MJB_DATA2"
$PN"CC16"114;
"MJB_DATA8"
$PN"CH16"115;
"MJB_DATA9"
$PN"CJ17"116;
"MJB_DATA10"
$PN"CJ16"117;
"MJB_DATA11"
$PN"CK18"118;
"MJB_DATA12"
$PN"CM16"119;
"MJB_DATA13"
$PN"CN17"120;
"MJB_DATA14"
$PN"CN16"121;
"MJB_DATA15"
$PN"CP18"122;
"MJB_DATA16"
$PN"CP16"123;
"MJB_DATA17"
$PN"CR17"124;
"MJB_DATA18"
$PN"CR16"125;
"MJB_DATA19"
$PN"CT18"95;
"MJB_DATA20"
$PN"CV16"96;
"MJB_DATA21"
$PN"CW17"97;
"MJB_DATA22"
$PN"CW16"98;
"MJB_DATA23"
$PN"CY18"99;
"MJB_DATA24"
$PN"CY16"100;
"MJB_DATA25"
$PN"DA17"101;
"MJB_DATA26"
$PN"DA16"102;
"MJB_DATA27"
$PN"DB18"103;
"MJB_DATA28"
$PN"DD16"104;
"MJB_DATA29"
$PN"DE17"105;
"MJB_DATA30"
$PN"DE16"106;
"MJB_DATA31"
$PN"DF16"107;
"MJB_DQS_H0"
$PN"CD16"60;
"MJB_DQS_H1"
$PN"CK16"61;
"MJB_DQS_H2"
$PN"CT16"62;
"MJB_DQS_H3"
$PN"DB16"54;
"MJB_DQS_H4"
$PN"BY18"55;
"MJB_DQS_H6"
$PN"CM18"56;
"MJB_DQS_H7"
$PN"CV18"57;
"MJB_DQS_H8"
$PN"DD18"41;
"MJB_DQS_H9"
$PN"BV16"42;
"MJB_DQS_L1"
$PN"CL16"47;
"MJB_DQS_L2"
$PN"CU16"48;
"MJB_DQS_L3"
$PN"DC16"49;
"MJB_DQS_L5"
$PN"CE17"50;
"MJB_DQS_L6"
$PN"CL17"51;
"MJB_DQS_L7"
$PN"CU17"52;
"MJB_DQS_L8"
$PN"DC17"39;
"MJB_DQS_L9"
$PN"BW16"40;
"MJB_PAR"
$PN"BL17"22;
"MJ_ALERT_L"
$PN"AT18"13;
"MJ_RESET_L"
$PN"AU17"24;
%"TAP"
"1","(-3250,5900)","0","mstr_standard","I161";
;
CDS_LIB"mstr_standard"
BODY_TYPE"PLUMBING"
HDL_TAP"TRUE";
"B \NAC \NWC"1;
"S \NAC"
BN"0"144;
%"TAP"
"1","(-3250,5850)","0","mstr_standard","I162";
;
CDS_LIB"mstr_standard"
BODY_TYPE"PLUMBING"
HDL_TAP"TRUE";
"B \NAC \NWC"1;
"S \NAC"
BN"1"145;
%"TAP"
"1","(-3250,5800)","0","mstr_standard","I163";
;
CDS_LIB"mstr_standard"
BODY_TYPE"PLUMBING"
HDL_TAP"TRUE";
"B \NAC \NWC"1;
"S \NAC"
BN"2"146;
%"TAP"
"1","(-3250,5700)","0","mstr_standard","I164";
;
CDS_LIB"mstr_standard"
BODY_TYPE"PLUMBING"
HDL_TAP"TRUE";
"B \NAC \NWC"1;
"S \NAC"
BN"4"148;
%"TAP"
"1","(-3250,5750)","0","mstr_standard","I165";
;
CDS_LIB"mstr_standard"
BODY_TYPE"PLUMBING"
HDL_TAP"TRUE";
"B \NAC \NWC"1;
"S \NAC"
BN"3"147;
%"TAP"
"1","(-3250,5650)","0","mstr_standard","I166";
;
CDS_LIB"mstr_standard"
BODY_TYPE"PLUMBING"
HDL_TAP"TRUE";
"B \NAC \NWC"1;
"S \NAC"
BN"5"149;
%"TAP"
"1","(-3250,5600)","0","mstr_standard","I167";
;
CDS_LIB"mstr_standard"
BODY_TYPE"PLUMBING"
HDL_TAP"TRUE";
"B \NAC \NWC"1;
"S \NAC"
BN"6"150;
%"TAP"
"1","(-3250,5550)","0","mstr_standard","I168";
;
CDS_LIB"mstr_standard"
BODY_TYPE"PLUMBING"
HDL_TAP"TRUE";
"B \NAC \NWC"1;
"S \NAC"
BN"7"151;
%"TAP"
"1","(-3250,5400)","0","mstr_standard","I169";
;
CDS_LIB"mstr_standard"
BODY_TYPE"PLUMBING"
HDL_TAP"TRUE";
"B \NAC \NWC"1;
"S \NAC"
BN"9"153;
%"TAP"
"1","(-3250,5450)","0","mstr_standard","I170";
;
CDS_LIB"mstr_standard"
BODY_TYPE"PLUMBING"
HDL_TAP"TRUE";
"B \NAC \NWC"1;
"S \NAC"
BN"8"152;
%"TAP"
"1","(-3250,5350)","0","mstr_standard","I171";
;
CDS_LIB"mstr_standard"
BODY_TYPE"PLUMBING"
HDL_TAP"TRUE";
"B \NAC \NWC"1;
"S \NAC"
BN"10"154;
%"TAP"
"1","(-3250,5300)","0","mstr_standard","I172";
;
CDS_LIB"mstr_standard"
BODY_TYPE"PLUMBING"
HDL_TAP"TRUE";
"B \NAC \NWC"1;
"S \NAC"
BN"11"155;
%"TAP"
"1","(-3250,5250)","0","mstr_standard","I173";
;
CDS_LIB"mstr_standard"
BODY_TYPE"PLUMBING"
HDL_TAP"TRUE";
"B \NAC \NWC"1;
"S \NAC"
BN"12"156;
%"TAP"
"1","(-3250,5200)","0","mstr_standard","I174";
;
CDS_LIB"mstr_standard"
BODY_TYPE"PLUMBING"
HDL_TAP"TRUE";
"B \NAC \NWC"1;
"S \NAC"
BN"13"157;
%"TAP"
"1","(-3250,5150)","0","mstr_standard","I175";
;
CDS_LIB"mstr_standard"
BODY_TYPE"PLUMBING"
HDL_TAP"TRUE";
"B \NAC \NWC"1;
"S \NAC"
BN"14"158;
%"TAP"
"1","(-3250,5100)","0","mstr_standard","I176";
;
CDS_LIB"mstr_standard"
BODY_TYPE"PLUMBING"
HDL_TAP"TRUE";
"B \NAC \NWC"1;
"S \NAC"
BN"15"129;
%"TAP"
"1","(-3250,5000)","0","mstr_standard","I177";
;
CDS_LIB"mstr_standard"
BODY_TYPE"PLUMBING"
HDL_TAP"TRUE";
"B \NAC \NWC"1;
"S \NAC"
BN"16"130;
%"TAP"
"1","(-3250,4950)","0","mstr_standard","I178";
;
CDS_LIB"mstr_standard"
BODY_TYPE"PLUMBING"
HDL_TAP"TRUE";
"B \NAC \NWC"1;
"S \NAC"
BN"17"131;
%"TAP"
"1","(-3250,4900)","0","mstr_standard","I179";
;
CDS_LIB"mstr_standard"
BODY_TYPE"PLUMBING"
HDL_TAP"TRUE";
"B \NAC \NWC"1;
"S \NAC"
BN"18"132;
%"TAP"
"1","(-3250,4850)","0","mstr_standard","I180";
;
CDS_LIB"mstr_standard"
BODY_TYPE"PLUMBING"
HDL_TAP"TRUE";
"B \NAC \NWC"1;
"S \NAC"
BN"19"133;
%"TAP"
"1","(-3250,4800)","0","mstr_standard","I181";
;
CDS_LIB"mstr_standard"
BODY_TYPE"PLUMBING"
HDL_TAP"TRUE";
"B \NAC \NWC"1;
"S \NAC"
BN"20"134;
%"TAP"
"1","(-3250,4750)","0","mstr_standard","I182";
;
CDS_LIB"mstr_standard"
BODY_TYPE"PLUMBING"
HDL_TAP"TRUE";
"B \NAC \NWC"1;
"S \NAC"
BN"21"135;
%"TAP"
"1","(-3250,4650)","0","mstr_standard","I183";
;
CDS_LIB"mstr_standard"
BODY_TYPE"PLUMBING"
HDL_TAP"TRUE";
"B \NAC \NWC"1;
"S \NAC"
BN"23"136;
%"TAP"
"1","(-3250,4700)","0","mstr_standard","I184";
;
CDS_LIB"mstr_standard"
BODY_TYPE"PLUMBING"
HDL_TAP"TRUE";
"B \NAC \NWC"1;
"S \NAC"
BN"22"128;
%"TAP"
"1","(-3250,4500)","0","mstr_standard","I185";
;
CDS_LIB"mstr_standard"
BODY_TYPE"PLUMBING"
HDL_TAP"TRUE";
"B \NAC \NWC"1;
"S \NAC"
BN"25"138;
%"TAP"
"1","(-3250,4550)","0","mstr_standard","I186";
;
CDS_LIB"mstr_standard"
BODY_TYPE"PLUMBING"
HDL_TAP"TRUE";
"B \NAC \NWC"1;
"S \NAC"
BN"24"137;
%"TAP"
"1","(-3250,4450)","0","mstr_standard","I187";
;
CDS_LIB"mstr_standard"
BODY_TYPE"PLUMBING"
HDL_TAP"TRUE";
"B \NAC \NWC"1;
"S \NAC"
BN"26"139;
%"TAP"
"1","(-3250,4400)","0","mstr_standard","I188";
;
CDS_LIB"mstr_standard"
BODY_TYPE"PLUMBING"
HDL_TAP"TRUE";
"B \NAC \NWC"1;
"S \NAC"
BN"27"140;
%"TAP"
"1","(-3250,4350)","0","mstr_standard","I189";
;
CDS_LIB"mstr_standard"
BODY_TYPE"PLUMBING"
HDL_TAP"TRUE";
"B \NAC \NWC"1;
"S \NAC"
BN"28"141;
%"TAP"
"1","(-3250,4300)","0","mstr_standard","I190";
;
CDS_LIB"mstr_standard"
BODY_TYPE"PLUMBING"
HDL_TAP"TRUE";
"B \NAC \NWC"1;
"S \NAC"
BN"29"142;
%"TAP"
"1","(-3250,4250)","0","mstr_standard","I191";
;
CDS_LIB"mstr_standard"
BODY_TYPE"PLUMBING"
HDL_TAP"TRUE";
"B \NAC \NWC"1;
"S \NAC"
BN"30"143;
%"TAP"
"1","(-3250,4100)","0","mstr_standard","I192";
;
CDS_LIB"mstr_standard"
BODY_TYPE"PLUMBING"
HDL_TAP"TRUE";
"B \NAC \NWC"2;
"S \NAC"
BN"0"127;
%"TAP"
"1","(-3250,4200)","0","mstr_standard","I193";
;
CDS_LIB"mstr_standard"
BODY_TYPE"PLUMBING"
HDL_TAP"TRUE";
"B \NAC \NWC"1;
"S \NAC"
BN"31"126;
%"TAP"
"1","(-3250,4000)","0","mstr_standard","I196";
;
CDS_LIB"mstr_standard"
BODY_TYPE"PLUMBING"
HDL_TAP"TRUE";
"B \NAC \NWC"2;
"S \NAC"
BN"2"114;
%"TAP"
"1","(-3250,4050)","0","mstr_standard","I197";
;
CDS_LIB"mstr_standard"
BODY_TYPE"PLUMBING"
HDL_TAP"TRUE";
"B \NAC \NWC"2;
"S \NAC"
BN"1"113;
%"TAP"
"1","(-3250,3900)","0","mstr_standard","I198";
;
CDS_LIB"mstr_standard"
BODY_TYPE"PLUMBING"
HDL_TAP"TRUE";
"B \NAC \NWC"2;
"S \NAC"
BN"4"112;
%"TAP"
"1","(-3250,3950)","0","mstr_standard","I199";
;
CDS_LIB"mstr_standard"
BODY_TYPE"PLUMBING"
HDL_TAP"TRUE";
"B \NAC \NWC"2;
"S \NAC"
BN"3"111;
%"TAP"
"1","(-3250,3850)","0","mstr_standard","I200";
;
CDS_LIB"mstr_standard"
BODY_TYPE"PLUMBING"
HDL_TAP"TRUE";
"B \NAC \NWC"2;
"S \NAC"
BN"5"110;
%"TAP"
"1","(-3250,3750)","0","mstr_standard","I201";
;
CDS_LIB"mstr_standard"
BODY_TYPE"PLUMBING"
HDL_TAP"TRUE";
"B \NAC \NWC"2;
"S \NAC"
BN"7"108;
%"TAP"
"1","(-3250,3800)","0","mstr_standard","I202";
;
CDS_LIB"mstr_standard"
BODY_TYPE"PLUMBING"
HDL_TAP"TRUE";
"B \NAC \NWC"2;
"S \NAC"
BN"6"109;
%"TAP"
"1","(-3250,3650)","0","mstr_standard","I203";
;
CDS_LIB"mstr_standard"
BODY_TYPE"PLUMBING"
HDL_TAP"TRUE";
"B \NAC \NWC"2;
"S \NAC"
BN"8"115;
%"TAP"
"1","(-3250,3600)","0","mstr_standard","I204";
;
CDS_LIB"mstr_standard"
BODY_TYPE"PLUMBING"
HDL_TAP"TRUE";
"B \NAC \NWC"2;
"S \NAC"
BN"9"116;
%"TAP"
"1","(-3250,3500)","0","mstr_standard","I205";
;
CDS_LIB"mstr_standard"
BODY_TYPE"PLUMBING"
HDL_TAP"TRUE";
"B \NAC \NWC"2;
"S \NAC"
BN"11"118;
%"TAP"
"1","(-3250,3550)","0","mstr_standard","I206";
;
CDS_LIB"mstr_standard"
BODY_TYPE"PLUMBING"
HDL_TAP"TRUE";
"B \NAC \NWC"2;
"S \NAC"
BN"10"117;
%"TAP"
"1","(-3250,3450)","0","mstr_standard","I207";
;
CDS_LIB"mstr_standard"
BODY_TYPE"PLUMBING"
HDL_TAP"TRUE";
"B \NAC \NWC"2;
"S \NAC"
BN"12"119;
%"TAP"
"1","(-3250,3400)","0","mstr_standard","I208";
;
CDS_LIB"mstr_standard"
BODY_TYPE"PLUMBING"
HDL_TAP"TRUE";
"B \NAC \NWC"2;
"S \NAC"
BN"13"120;
%"TAP"
"1","(-3250,3350)","0","mstr_standard","I209";
;
CDS_LIB"mstr_standard"
BODY_TYPE"PLUMBING"
HDL_TAP"TRUE";
"B \NAC \NWC"2;
"S \NAC"
BN"14"121;
%"TAP"
"1","(-3250,3300)","0","mstr_standard","I210";
;
CDS_LIB"mstr_standard"
BODY_TYPE"PLUMBING"
HDL_TAP"TRUE";
"B \NAC \NWC"2;
"S \NAC"
BN"15"122;
%"TAP"
"1","(-3250,3200)","0","mstr_standard","I211";
;
CDS_LIB"mstr_standard"
BODY_TYPE"PLUMBING"
HDL_TAP"TRUE";
"B \NAC \NWC"2;
"S \NAC"
BN"16"123;
%"TAP"
"1","(-3250,3150)","0","mstr_standard","I212";
;
CDS_LIB"mstr_standard"
BODY_TYPE"PLUMBING"
HDL_TAP"TRUE";
"B \NAC \NWC"2;
"S \NAC"
BN"17"124;
%"TAP"
"1","(-3250,3100)","0","mstr_standard","I213";
;
CDS_LIB"mstr_standard"
BODY_TYPE"PLUMBING"
HDL_TAP"TRUE";
"B \NAC \NWC"2;
"S \NAC"
BN"18"125;
%"TAP"
"1","(-3250,2950)","0","mstr_standard","I214";
;
CDS_LIB"mstr_standard"
BODY_TYPE"PLUMBING"
HDL_TAP"TRUE";
"B \NAC \NWC"2;
"S \NAC"
BN"21"97;
%"TAP"
"1","(-3250,3000)","0","mstr_standard","I215";
;
CDS_LIB"mstr_standard"
BODY_TYPE"PLUMBING"
HDL_TAP"TRUE";
"B \NAC \NWC"2;
"S \NAC"
BN"20"96;
%"TAP"
"1","(-3250,3050)","0","mstr_standard","I216";
;
CDS_LIB"mstr_standard"
BODY_TYPE"PLUMBING"
HDL_TAP"TRUE";
"B \NAC \NWC"2;
"S \NAC"
BN"19"95;
%"TAP"
"1","(-3250,2900)","0","mstr_standard","I217";
;
CDS_LIB"mstr_standard"
BODY_TYPE"PLUMBING"
HDL_TAP"TRUE";
"B \NAC \NWC"2;
"S \NAC"
BN"22"98;
%"TAP"
"1","(-3250,2850)","0","mstr_standard","I218";
;
CDS_LIB"mstr_standard"
BODY_TYPE"PLUMBING"
HDL_TAP"TRUE";
"B \NAC \NWC"2;
"S \NAC"
BN"23"99;
%"TAP"
"1","(-3250,2700)","0","mstr_standard","I219";
;
CDS_LIB"mstr_standard"
BODY_TYPE"PLUMBING"
HDL_TAP"TRUE";
"B \NAC \NWC"2;
"S \NAC"
BN"25"101;
%"TAP"
"1","(-3250,2750)","0","mstr_standard","I220";
;
CDS_LIB"mstr_standard"
BODY_TYPE"PLUMBING"
HDL_TAP"TRUE";
"B \NAC \NWC"2;
"S \NAC"
BN"24"100;
%"TAP"
"1","(-3250,2650)","0","mstr_standard","I221";
;
CDS_LIB"mstr_standard"
BODY_TYPE"PLUMBING"
HDL_TAP"TRUE";
"B \NAC \NWC"2;
"S \NAC"
BN"26"102;
%"TAP"
"1","(-3250,2600)","0","mstr_standard","I222";
;
CDS_LIB"mstr_standard"
BODY_TYPE"PLUMBING"
HDL_TAP"TRUE";
"B \NAC \NWC"2;
"S \NAC"
BN"27"103;
%"TAP"
"1","(-3250,2450)","0","mstr_standard","I223";
;
CDS_LIB"mstr_standard"
BODY_TYPE"PLUMBING"
HDL_TAP"TRUE";
"B \NAC \NWC"2;
"S \NAC"
BN"30"106;
%"TAP"
"1","(-3250,2550)","0","mstr_standard","I224";
;
CDS_LIB"mstr_standard"
BODY_TYPE"PLUMBING"
HDL_TAP"TRUE";
"B \NAC \NWC"2;
"S \NAC"
BN"28"104;
%"TAP"
"1","(-3250,2500)","0","mstr_standard","I225";
;
CDS_LIB"mstr_standard"
BODY_TYPE"PLUMBING"
HDL_TAP"TRUE";
"B \NAC \NWC"2;
"S \NAC"
BN"29"105;
%"TAP"
"1","(-3250,2400)","0","mstr_standard","I226";
;
CDS_LIB"mstr_standard"
BODY_TYPE"PLUMBING"
HDL_TAP"TRUE";
"B \NAC \NWC"2;
"S \NAC"
BN"31"107;
%"TAP"
"1","(-3250,2300)","0","mstr_standard","I227";
;
CDS_LIB"mstr_standard"
BODY_TYPE"PLUMBING"
HDL_TAP"TRUE";
"B \NAC \NWC"3;
"S \NAC"
BN"0"89;
%"TAP"
"1","(-3250,2250)","0","mstr_standard","I228";
;
CDS_LIB"mstr_standard"
BODY_TYPE"PLUMBING"
HDL_TAP"TRUE";
"B \NAC \NWC"3;
"S \NAC"
BN"1"90;
%"TAP"
"1","(-3250,2200)","0","mstr_standard","I229";
;
CDS_LIB"mstr_standard"
BODY_TYPE"PLUMBING"
HDL_TAP"TRUE";
"B \NAC \NWC"3;
"S \NAC"
BN"2"91;
%"TAP"
"1","(-3250,2150)","0","mstr_standard","I230";
;
CDS_LIB"mstr_standard"
BODY_TYPE"PLUMBING"
HDL_TAP"TRUE";
"B \NAC \NWC"3;
"S \NAC"
BN"3"92;
%"TAP"
"1","(-3250,2100)","0","mstr_standard","I231";
;
CDS_LIB"mstr_standard"
BODY_TYPE"PLUMBING"
HDL_TAP"TRUE";
"B \NAC \NWC"3;
"S \NAC"
BN"4"93;
%"TAP"
"1","(-3250,2050)","0","mstr_standard","I232";
;
CDS_LIB"mstr_standard"
BODY_TYPE"PLUMBING"
HDL_TAP"TRUE";
"B \NAC \NWC"3;
"S \NAC"
BN"5"94;
%"TAP"
"1","(-3250,1950)","0","mstr_standard","I234";
;
CDS_LIB"mstr_standard"
BODY_TYPE"PLUMBING"
HDL_TAP"TRUE";
"B \NAC \NWC"3;
"S \NAC"
BN"7"80;
%"TAP"
"1","(-3250,2000)","0","mstr_standard","I235";
;
CDS_LIB"mstr_standard"
BODY_TYPE"PLUMBING"
HDL_TAP"TRUE";
"B \NAC \NWC"3;
"S \NAC"
BN"6"79;
%"TAP"
"1","(-3250,1800)","0","mstr_standard","I236";
;
CDS_LIB"mstr_standard"
BODY_TYPE"PLUMBING"
HDL_TAP"TRUE";
"B \NAC \NWC"4;
"S \NAC"
BN"1"82;
%"TAP"
"1","(-3250,1850)","0","mstr_standard","I237";
;
CDS_LIB"mstr_standard"
BODY_TYPE"PLUMBING"
HDL_TAP"TRUE";
"B \NAC \NWC"4;
"S \NAC"
BN"0"81;
%"TAP"
"1","(-3250,1700)","0","mstr_standard","I238";
;
CDS_LIB"mstr_standard"
BODY_TYPE"PLUMBING"
HDL_TAP"TRUE";
"B \NAC \NWC"4;
"S \NAC"
BN"3"84;
%"TAP"
"1","(-3250,1750)","0","mstr_standard","I239";
;
CDS_LIB"mstr_standard"
BODY_TYPE"PLUMBING"
HDL_TAP"TRUE";
"B \NAC \NWC"4;
"S \NAC"
BN"2"83;
%"TAP"
"1","(-3250,1650)","0","mstr_standard","I240";
;
CDS_LIB"mstr_standard"
BODY_TYPE"PLUMBING"
HDL_TAP"TRUE";
"B \NAC \NWC"4;
"S \NAC"
BN"4"85;
%"TAP"
"1","(-3250,1600)","0","mstr_standard","I241";
;
CDS_LIB"mstr_standard"
BODY_TYPE"PLUMBING"
HDL_TAP"TRUE";
"B \NAC \NWC"4;
"S \NAC"
BN"5"86;
%"TAP"
"1","(-3250,1550)","0","mstr_standard","I242";
;
CDS_LIB"mstr_standard"
BODY_TYPE"PLUMBING"
HDL_TAP"TRUE";
"B \NAC \NWC"4;
"S \NAC"
BN"6"87;
%"TAP"
"1","(-3250,1500)","0","mstr_standard","I243";
;
CDS_LIB"mstr_standard"
BODY_TYPE"PLUMBING"
HDL_TAP"TRUE";
"B \NAC \NWC"4;
"S \NAC"
BN"7"88;
%"TAP"
"1","(-5675,5900)","2","mstr_standard","I244";
;
CDS_LIB"mstr_standard"
BODY_TYPE"PLUMBING"
HDL_TAP"TRUE";
"B \NAC \NWC"5;
"S \NAC"
BN"0"76;
%"TAP"
"1","(-5675,5800)","2","mstr_standard","I245";
;
CDS_LIB"mstr_standard"
BODY_TYPE"PLUMBING"
HDL_TAP"TRUE";
"B \NAC \NWC"5;
"S \NAC"
BN"1"77;
%"TAP"
"1","(-5675,5700)","2","mstr_standard","I246";
;
CDS_LIB"mstr_standard"
BODY_TYPE"PLUMBING"
HDL_TAP"TRUE";
"B \NAC \NWC"5;
"S \NAC"
BN"2"78;
%"TAP"
"1","(-5675,5600)","2","mstr_standard","I247";
;
CDS_LIB"mstr_standard"
BODY_TYPE"PLUMBING"
HDL_TAP"TRUE";
"B \NAC \NWC"5;
"S \NAC"
BN"3"72;
%"TAP"
"1","(-5675,5500)","2","mstr_standard","I248";
;
CDS_LIB"mstr_standard"
BODY_TYPE"PLUMBING"
HDL_TAP"TRUE";
"B \NAC \NWC"5;
"S \NAC"
BN"4"71;
%"TAP"
"1","(-5675,5400)","2","mstr_standard","I249";
;
CDS_LIB"mstr_standard"
BODY_TYPE"PLUMBING"
HDL_TAP"TRUE";
"B \NAC \NWC"5;
"S \NAC"
BN"5"73;
%"TAP"
"1","(-5675,5300)","2","mstr_standard","I250";
;
CDS_LIB"mstr_standard"
BODY_TYPE"PLUMBING"
HDL_TAP"TRUE";
"B \NAC \NWC"5;
"S \NAC"
BN"6"74;
%"TAP"
"1","(-5675,5200)","2","mstr_standard","I251";
;
CDS_LIB"mstr_standard"
BODY_TYPE"PLUMBING"
HDL_TAP"TRUE";
"B \NAC \NWC"5;
"S \NAC"
BN"7"75;
%"TAP"
"1","(-5875,5850)","2","mstr_standard","I252";
;
CDS_LIB"mstr_standard"
BODY_TYPE"PLUMBING"
HDL_TAP"TRUE";
"B \NAC \NWC"9;
"S \NAC"
BN"0"66;
%"TAP"
"1","(-5875,5650)","2","mstr_standard","I253";
;
CDS_LIB"mstr_standard"
BODY_TYPE"PLUMBING"
HDL_TAP"TRUE";
"B \NAC \NWC"9;
"S \NAC"
BN"2"68;
%"TAP"
"1","(-5875,5750)","2","mstr_standard","I254";
;
CDS_LIB"mstr_standard"
BODY_TYPE"PLUMBING"
HDL_TAP"TRUE";
"B \NAC \NWC"9;
"S \NAC"
BN"1"67;
%"TAP"
"1","(-5875,5550)","2","mstr_standard","I255";
;
CDS_LIB"mstr_standard"
BODY_TYPE"PLUMBING"
HDL_TAP"TRUE";
"B \NAC \NWC"9;
"S \NAC"
BN"3"69;
%"TAP"
"1","(-5875,5450)","2","mstr_standard","I256";
;
CDS_LIB"mstr_standard"
BODY_TYPE"PLUMBING"
HDL_TAP"TRUE";
"B \NAC \NWC"9;
"S \NAC"
BN"4"63;
%"TAP"
"1","(-5875,5250)","2","mstr_standard","I257";
;
CDS_LIB"mstr_standard"
BODY_TYPE"PLUMBING"
HDL_TAP"TRUE";
"B \NAC \NWC"9;
"S \NAC"
BN"6"70;
%"TAP"
"1","(-5875,5350)","2","mstr_standard","I258";
;
CDS_LIB"mstr_standard"
BODY_TYPE"PLUMBING"
HDL_TAP"TRUE";
"B \NAC \NWC"9;
"S \NAC"
BN"5"64;
%"TAP"
"1","(-5875,5150)","2","mstr_standard","I259";
;
CDS_LIB"mstr_standard"
BODY_TYPE"PLUMBING"
HDL_TAP"TRUE";
"B \NAC \NWC"9;
"S \NAC"
BN"7"65;
%"TAP"
"1","(-5675,5000)","2","mstr_standard","I260";
;
CDS_LIB"mstr_standard"
BODY_TYPE"PLUMBING"
HDL_TAP"TRUE";
"B \NAC \NWC"5;
"S \NAC"
BN"9"59;
%"TAP"
"1","(-5675,5100)","2","mstr_standard","I261";
;
CDS_LIB"mstr_standard"
BODY_TYPE"PLUMBING"
HDL_TAP"TRUE";
"B \NAC \NWC"5;
"S \NAC"
BN"8"58;
%"TAP"
"1","(-5675,4850)","2","mstr_standard","I262";
;
CDS_LIB"mstr_standard"
BODY_TYPE"PLUMBING"
HDL_TAP"TRUE";
"B \NAC \NWC"6;
"S \NAC"
BN"0"60;
%"TAP"
"1","(-5675,4750)","2","mstr_standard","I263";
;
CDS_LIB"mstr_standard"
BODY_TYPE"PLUMBING"
HDL_TAP"TRUE";
"B \NAC \NWC"6;
"S \NAC"
BN"1"61;
%"TAP"
"1","(-5675,4650)","2","mstr_standard","I264";
;
CDS_LIB"mstr_standard"
BODY_TYPE"PLUMBING"
HDL_TAP"TRUE";
"B \NAC \NWC"6;
"S \NAC"
BN"2"62;
%"TAP"
"1","(-5675,4550)","2","mstr_standard","I265";
;
CDS_LIB"mstr_standard"
BODY_TYPE"PLUMBING"
HDL_TAP"TRUE";
"B \NAC \NWC"6;
"S \NAC"
BN"3"54;
%"TAP"
"1","(-5675,4450)","2","mstr_standard","I266";
;
CDS_LIB"mstr_standard"
BODY_TYPE"PLUMBING"
HDL_TAP"TRUE";
"B \NAC \NWC"6;
"S \NAC"
BN"4"55;
%"TAP"
"1","(-5675,4350)","2","mstr_standard","I267";
;
CDS_LIB"mstr_standard"
BODY_TYPE"PLUMBING"
HDL_TAP"TRUE";
"B \NAC \NWC"6;
"S \NAC"
BN"5"53;
%"TAP"
"1","(-5675,4250)","2","mstr_standard","I268";
;
CDS_LIB"mstr_standard"
BODY_TYPE"PLUMBING"
HDL_TAP"TRUE";
"B \NAC \NWC"6;
"S \NAC"
BN"6"56;
%"TAP"
"1","(-5675,4150)","2","mstr_standard","I269";
;
CDS_LIB"mstr_standard"
BODY_TYPE"PLUMBING"
HDL_TAP"TRUE";
"B \NAC \NWC"6;
"S \NAC"
BN"7"57;
%"TAP"
"1","(-5875,4950)","2","mstr_standard","I270";
;
CDS_LIB"mstr_standard"
BODY_TYPE"PLUMBING"
HDL_TAP"TRUE";
"B \NAC \NWC"9;
"S \NAC"
BN"9"46;
%"TAP"
"1","(-5875,5050)","2","mstr_standard","I271";
;
CDS_LIB"mstr_standard"
BODY_TYPE"PLUMBING"
HDL_TAP"TRUE";
"B \NAC \NWC"9;
"S \NAC"
BN"8"45;
%"TAP"
"1","(-5875,4800)","2","mstr_standard","I272";
;
CDS_LIB"mstr_standard"
BODY_TYPE"PLUMBING"
HDL_TAP"TRUE";
"B \NAC \NWC"10;
"S \NAC"
BN"0"44;
%"TAP"
"1","(-5875,4700)","2","mstr_standard","I273";
;
CDS_LIB"mstr_standard"
BODY_TYPE"PLUMBING"
HDL_TAP"TRUE";
"B \NAC \NWC"10;
"S \NAC"
BN"1"47;
%"TAP"
"1","(-5875,4500)","2","mstr_standard","I274";
;
CDS_LIB"mstr_standard"
BODY_TYPE"PLUMBING"
HDL_TAP"TRUE";
"B \NAC \NWC"10;
"S \NAC"
BN"3"49;
%"TAP"
"1","(-5875,4600)","2","mstr_standard","I275";
;
CDS_LIB"mstr_standard"
BODY_TYPE"PLUMBING"
HDL_TAP"TRUE";
"B \NAC \NWC"10;
"S \NAC"
BN"2"48;
%"TAP"
"1","(-5875,4400)","2","mstr_standard","I276";
;
CDS_LIB"mstr_standard"
BODY_TYPE"PLUMBING"
HDL_TAP"TRUE";
"B \NAC \NWC"10;
"S \NAC"
BN"4"43;
%"TAP"
"1","(-5875,4300)","2","mstr_standard","I277";
;
CDS_LIB"mstr_standard"
BODY_TYPE"PLUMBING"
HDL_TAP"TRUE";
"B \NAC \NWC"10;
"S \NAC"
BN"5"50;
%"TAP"
"1","(-5875,4100)","2","mstr_standard","I278";
;
CDS_LIB"mstr_standard"
BODY_TYPE"PLUMBING"
HDL_TAP"TRUE";
"B \NAC \NWC"10;
"S \NAC"
BN"7"52;
%"TAP"
"1","(-5875,4200)","2","mstr_standard","I279";
;
CDS_LIB"mstr_standard"
BODY_TYPE"PLUMBING"
HDL_TAP"TRUE";
"B \NAC \NWC"10;
"S \NAC"
BN"6"51;
%"TAP"
"1","(-5675,4050)","2","mstr_standard","I284";
;
CDS_LIB"mstr_standard"
BODY_TYPE"PLUMBING"
HDL_TAP"TRUE";
"B \NAC \NWC"6;
"S \NAC"
BN"8"41;
%"TAP"
"1","(-5675,3950)","2","mstr_standard","I285";
;
CDS_LIB"mstr_standard"
BODY_TYPE"PLUMBING"
HDL_TAP"TRUE";
"B \NAC \NWC"6;
"S \NAC"
BN"9"42;
%"TAP"
"1","(-5875,4000)","2","mstr_standard","I286";
;
CDS_LIB"mstr_standard"
BODY_TYPE"PLUMBING"
HDL_TAP"TRUE";
"B \NAC \NWC"10;
"S \NAC"
BN"8"39;
%"TAP"
"1","(-5875,3900)","2","mstr_standard","I287";
;
CDS_LIB"mstr_standard"
BODY_TYPE"PLUMBING"
HDL_TAP"TRUE";
"B \NAC \NWC"10;
"S \NAC"
BN"9"40;
%"TAP"
"1","(-5875,3750)","2","mstr_standard","I288";
;
CDS_LIB"mstr_standard"
BODY_TYPE"PLUMBING"
HDL_TAP"TRUE";
"B \NAC \NWC"8;
"S \NAC"
BN"0"28;
%"TAP"
"1","(-5875,3700)","2","mstr_standard","I289";
;
CDS_LIB"mstr_standard"
BODY_TYPE"PLUMBING"
HDL_TAP"TRUE";
"B \NAC \NWC"8;
"S \NAC"
BN"1"29;
%"TAP"
"1","(-5875,3600)","2","mstr_standard","I290";
;
CDS_LIB"mstr_standard"
BODY_TYPE"PLUMBING"
HDL_TAP"TRUE";
"B \NAC \NWC"8;
"S \NAC"
BN"3"31;
%"TAP"
"1","(-5875,3650)","2","mstr_standard","I291";
;
CDS_LIB"mstr_standard"
BODY_TYPE"PLUMBING"
HDL_TAP"TRUE";
"B \NAC \NWC"8;
"S \NAC"
BN"2"30;
%"TAP"
"1","(-5875,3550)","2","mstr_standard","I292";
;
CDS_LIB"mstr_standard"
BODY_TYPE"PLUMBING"
HDL_TAP"TRUE";
"B \NAC \NWC"8;
"S \NAC"
BN"4"32;
%"TAP"
"1","(-5875,3500)","2","mstr_standard","I293";
;
CDS_LIB"mstr_standard"
BODY_TYPE"PLUMBING"
HDL_TAP"TRUE";
"B \NAC \NWC"8;
"S \NAC"
BN"5"26;
%"TAP"
"1","(-5875,3450)","2","mstr_standard","I294";
;
CDS_LIB"mstr_standard"
BODY_TYPE"PLUMBING"
HDL_TAP"TRUE";
"B \NAC \NWC"8;
"S \NAC"
BN"6"27;
%"TAP"
"1","(-5875,3350)","2","mstr_standard","I295";
;
CDS_LIB"mstr_standard"
BODY_TYPE"PLUMBING"
HDL_TAP"TRUE";
"B \NAC \NWC"7;
"S \NAC"
BN"0"33;
%"TAP"
"1","(-5875,3250)","2","mstr_standard","I296";
;
CDS_LIB"mstr_standard"
BODY_TYPE"PLUMBING"
HDL_TAP"TRUE";
"B \NAC \NWC"7;
"S \NAC"
BN"2"35;
%"TAP"
"1","(-5875,3300)","2","mstr_standard","I297";
;
CDS_LIB"mstr_standard"
BODY_TYPE"PLUMBING"
HDL_TAP"TRUE";
"B \NAC \NWC"7;
"S \NAC"
BN"1"34;
%"TAP"
"1","(-5875,3200)","2","mstr_standard","I298";
;
CDS_LIB"mstr_standard"
BODY_TYPE"PLUMBING"
HDL_TAP"TRUE";
"B \NAC \NWC"7;
"S \NAC"
BN"3"36;
%"TAP"
"1","(-5875,3150)","2","mstr_standard","I299";
;
CDS_LIB"mstr_standard"
BODY_TYPE"PLUMBING"
HDL_TAP"TRUE";
"B \NAC \NWC"7;
"S \NAC"
BN"4"37;
%"TAP"
"1","(-5875,3100)","2","mstr_standard","I300";
;
CDS_LIB"mstr_standard"
BODY_TYPE"PLUMBING"
HDL_TAP"TRUE";
"B \NAC \NWC"7;
"S \NAC"
BN"5"38;
%"TAP"
"1","(-5875,3050)","2","mstr_standard","I301";
;
CDS_LIB"mstr_standard"
BODY_TYPE"PLUMBING"
HDL_TAP"TRUE";
"B \NAC \NWC"7;
"S \NAC"
BN"6"25;
%"Q_RES"
"1","(-6550,2050)","0","pure_quanta","I314";
;
LOCATION"R509"
$SEC"1"
CDS_SEC"1"
TOLERANCE"1%"
VALUE"15   "
PART_NUMBER"CS01502FB11"
PACK_TYPE"0402LF"
CDS_LIB"pure_quanta"
WATTAGE"1/16W"
MATERIAL"CHIP";
"B"
$PN"2"13;
"A"
$PN"1"11;
END.
